(kicad_pcb
	(version 20260206)
	(generator "pcbnew")
	(generator_version "10.0")
	(general
		(thickness 1.6)
		(legacy_teardrops no)
	)
	(paper "A4")
	(title_block
		(title "Wiwynn_Tioga_Pass_MB.brd")
		(comment 1 "Tioga Pass / footprints 279-285 of 4770")
	)
	(layers
		(0 "F.Cu" signal "TOP")
		(4 "In1.Cu" signal "L2GND")
		(6 "In2.Cu" signal "L3")
		(8 "In3.Cu" signal "L4GND")
		(10 "In4.Cu" signal "L5")
		(12 "In5.Cu" signal "L6GND")
		(14 "In6.Cu" signal "L7VCC")
		(16 "In7.Cu" signal "L8VCC")
		(18 "In8.Cu" signal "L9GND")
		(20 "In9.Cu" signal "L10")
		(22 "In10.Cu" signal "L11GND")
		(24 "In11.Cu" signal "L12")
		(26 "In12.Cu" signal "L13GND")
		(2 "B.Cu" signal "BOTTOM")
		(9 "F.Adhes" user "F.Adhesive")
		(11 "B.Adhes" user "B.Adhesive")
		(13 "F.Paste" user "Package Geometry/Pastemask Top")
		(15 "B.Paste" user "Package Geometry/Pastemask Bottom")
		(5 "F.SilkS" user "Ref Des/Silkscreen Top")
		(7 "B.SilkS" user "Ref Des/Silkscreen Bottom")
		(1 "F.Mask" user "Board Geometry/Soldermask Top")
		(3 "B.Mask" user "Board Geometry/Soldermask Bottom")
		(17 "Dwgs.User" user "User.Drawings")
		(19 "Cmts.User" user "User.Comments")
		(21 "Eco1.User" user "User.Eco1")
		(23 "Eco2.User" user "User.Eco2")
		(25 "Edge.Cuts" user "Board Geometry/Outline")
		(27 "Margin" user)
		(31 "F.CrtYd" user "Package Geometry/Place Bound Top")
		(29 "B.CrtYd" user "Package Geometry/Place Bound Bottom")
		(35 "F.Fab" user "Ref Des/Assembly Top")
		(33 "B.Fab" user "Ref Des/Assembly Bottom")
	)
	(footprint ""
		(layer "F.Cu")
		(at 8.509 -147.32)
		(property "Reference" "L1A1"
			(at 3.378708 -4.251706 0)
			(unlocked yes)
			(layer "F.SilkS")
			(effects
				(font
					(size 0.4064 0.254)
					(thickness 0.1524)
				)
			)
		)
		(property "Value" ""
			(at 0 0 0)
			(layer "F.Fab")
			(effects
				(font
					(size 1.27 1.27)
				)
			)
		)
		(duplicate_pad_numbers_are_jumpers no)
		(fp_line
			(start -1.1303 -3.199892)
			(end 8.3693 -3.199892)
			(stroke
				(width 0.1524)
				(type default)
			)
			(layer "F.SilkS")
		)
		(fp_line
			(start -1.1303 -1.6637)
			(end -1.1303 -3.199892)
			(stroke
				(width 0.1524)
				(type default)
			)
			(layer "F.SilkS")
		)
		(fp_line
			(start -1.1303 3.199892)
			(end -1.1303 1.6637)
			(stroke
				(width 0.1524)
				(type default)
			)
			(layer "F.SilkS")
		)
		(fp_line
			(start 8.3693 -3.199892)
			(end 8.3693 -1.6637)
			(stroke
				(width 0.1524)
				(type default)
			)
			(layer "F.SilkS")
		)
		(fp_line
			(start 8.3693 1.6637)
			(end 8.3693 3.199892)
			(stroke
				(width 0.1524)
				(type default)
			)
			(layer "F.SilkS")
		)
		(fp_line
			(start 8.3693 3.199892)
			(end -1.1303 3.199892)
			(stroke
				(width 0.1524)
				(type default)
			)
			(layer "F.SilkS")
		)
		(fp_rect
			(start -1.1303 3.199892)
			(end 8.3693 -3.199892)
			(stroke
				(width 0)
				(type default)
			)
			(fill no)
			(layer "F.CrtYd")
		)
		(fp_line
			(start -1.1303 -3.199892)
			(end 8.3693 -3.199892)
			(stroke
				(width 0.1)
				(type default)
			)
			(layer "F.Fab")
		)
		(fp_line
			(start -1.1303 3.199892)
			(end -1.1303 -3.199892)
			(stroke
				(width 0.1)
				(type default)
			)
			(layer "F.Fab")
		)
		(fp_line
			(start 8.3693 -3.199892)
			(end 8.3693 3.199892)
			(stroke
				(width 0.1)
				(type default)
			)
			(layer "F.Fab")
		)
		(fp_line
			(start 8.3693 3.199892)
			(end -1.1303 3.199892)
			(stroke
				(width 0.1)
				(type default)
			)
			(layer "F.Fab")
		)
		(pad "1" smd rect
			(at 0 0)
			(size 3.683 2.667)
			(layers "F.Cu" "F.Mask" "F.Paste")
			(net "VR_PVDDQ_KLM_PH2_SW")
		)
		(pad "2" smd rect
			(at 7.239 0)
			(size 3.683 2.667)
			(layers "F.Cu" "F.Mask" "F.Paste")
			(net "PVDDQ_KLM")
		)
	)
	(footprint ""
		(layer "F.Cu")
		(at 189.484 -56.642)
		(property "Reference" "C4E16"
			(at -4.16433 4.064 90)
			(unlocked yes)
			(layer "F.SilkS")
			(effects
				(font
					(size 0.7874 0.5842)
					(thickness 0.1524)
				)
				(justify left)
			)
		)
		(property "Value" ""
			(at 0 0 0)
			(layer "F.Fab")
			(effects
				(font
					(size 1.27 1.27)
				)
			)
		)
		(duplicate_pad_numbers_are_jumpers no)
		(fp_line
			(start -3.400044 0.028956)
			(end -3.400044 6.06679)
			(stroke
				(width 0.1524)
				(type default)
			)
			(layer "F.SilkS")
		)
		(fp_line
			(start -3.400044 6.06679)
			(end -0.9017 6.06679)
			(stroke
				(width 0.1524)
				(type default)
			)
			(layer "F.SilkS")
		)
		(fp_line
			(start -2.638044 -0.733044)
			(end -3.400044 0.028956)
			(stroke
				(width 0.1524)
				(type default)
			)
			(layer "F.SilkS")
		)
		(fp_line
			(start -0.9017 -1.714246)
			(end -0.9017 1.587754)
			(stroke
				(width 0.1524)
				(type default)
			)
			(layer "F.SilkS")
		)
		(fp_line
			(start -0.9017 -0.733044)
			(end -2.638044 -0.733044)
			(stroke
				(width 0.1524)
				(type default)
			)
			(layer "F.SilkS")
		)
		(fp_line
			(start -0.9017 1.587754)
			(end -0.7239 1.587754)
			(stroke
				(width 0.1524)
				(type default)
			)
			(layer "F.SilkS")
		)
		(fp_line
			(start -0.7239 -1.714246)
			(end -0.9017 -1.714246)
			(stroke
				(width 0.1524)
				(type default)
			)
			(layer "F.SilkS")
		)
		(fp_line
			(start 0.7239 1.587754)
			(end 0.9017 1.587754)
			(stroke
				(width 0.1524)
				(type default)
			)
			(layer "F.SilkS")
		)
		(fp_line
			(start 0.9017 -1.714246)
			(end 0.7239 -1.714246)
			(stroke
				(width 0.1524)
				(type default)
			)
			(layer "F.SilkS")
		)
		(fp_line
			(start 0.9017 1.587754)
			(end 0.9017 -1.714246)
			(stroke
				(width 0.1524)
				(type default)
			)
			(layer "F.SilkS")
		)
		(fp_line
			(start 0.9017 6.06679)
			(end 3.400044 6.06679)
			(stroke
				(width 0.1524)
				(type default)
			)
			(layer "F.SilkS")
		)
		(fp_line
			(start 2.638044 -0.733044)
			(end 0.9017 -0.733044)
			(stroke
				(width 0.1524)
				(type default)
			)
			(layer "F.SilkS")
		)
		(fp_line
			(start 3.400044 0.028956)
			(end 2.638044 -0.733044)
			(stroke
				(width 0.1524)
				(type default)
			)
			(layer "F.SilkS")
		)
		(fp_line
			(start 3.400044 6.06679)
			(end 3.400044 0.028956)
			(stroke
				(width 0.1524)
				(type default)
			)
			(layer "F.SilkS")
		)
		(fp_poly
			(pts
				(xy -3.400044 6.06679) (xy 3.400044 6.06679) (xy 3.400044 0.028956) (xy 2.638044 -0.733044) (xy -2.638044 -0.733044)
				(xy -3.400044 0.028956)
			)
			(stroke
				(width 0)
				(type default)
			)
			(fill no)
			(layer "F.CrtYd")
		)
		(fp_line
			(start -3.400044 0.028956)
			(end -3.400044 6.06679)
			(stroke
				(width 0.1)
				(type default)
			)
			(layer "F.Fab")
		)
		(fp_line
			(start -3.400044 6.06679)
			(end 3.400044 6.06679)
			(stroke
				(width 0.1)
				(type default)
			)
			(layer "F.Fab")
		)
		(fp_line
			(start -2.638044 -0.733044)
			(end -3.400044 0.028956)
			(stroke
				(width 0.1)
				(type default)
			)
			(layer "F.Fab")
		)
		(fp_line
			(start 2.638044 -0.733044)
			(end -2.638044 -0.733044)
			(stroke
				(width 0.1)
				(type default)
			)
			(layer "F.Fab")
		)
		(fp_line
			(start 3.400044 0.028956)
			(end 2.638044 -0.733044)
			(stroke
				(width 0.1)
				(type default)
			)
			(layer "F.Fab")
		)
		(fp_line
			(start 3.400044 6.06679)
			(end 3.400044 0.028956)
			(stroke
				(width 0.1)
				(type default)
			)
			(layer "F.Fab")
		)
		(fp_circle
			(center 0 2.667)
			(end 3.400044 2.667)
			(stroke
				(width 0.1)
				(type default)
			)
			(fill no)
			(layer "F.Fab")
		)
		(pad "1" smd rect
			(at 0 0)
			(size 0.7874 3.429)
			(layers "F.Cu" "F.Mask" "F.Paste")
			(net "VR_FET_SW_P12V_STBY_PVCCIN_CPU0")
		)
		(pad "2" smd rect
			(at 0 5.334)
			(size 0.7874 3.429)
			(layers "F.Cu" "F.Mask" "F.Paste")
			(net "GND")
		)
	)
	(footprint ""
		(layer "F.Cu")
		(at -2.5146 -127.7112 -90)
		(property "Reference" "R1B10"
			(at 0 0 270)
			(layer "F.SilkS")
			(hide yes)
			(effects
				(font
					(size 1.27 1.27)
				)
			)
		)
		(property "Value" ""
			(at 0 0 270)
			(layer "F.Fab")
			(effects
				(font
					(size 1.27 1.27)
				)
			)
		)
		(duplicate_pad_numbers_are_jumpers no)
		(fp_rect
			(start 0.2794 0.9906)
			(end -0.2794 -0.1016)
			(stroke
				(width 0)
				(type default)
			)
			(fill no)
			(layer "F.CrtYd")
		)
		(fp_line
			(start -0.2794 0.9906)
			(end 0.2794 0.9906)
			(stroke
				(width 0.1)
				(type default)
			)
			(layer "F.Fab")
		)
		(fp_line
			(start 0.2794 0.9906)
			(end 0.2794 -0.1016)
			(stroke
				(width 0.1)
				(type default)
			)
			(layer "F.Fab")
		)
		(fp_line
			(start -0.2794 -0.1016)
			(end -0.2794 0.9906)
			(stroke
				(width 0.1)
				(type default)
			)
			(layer "F.Fab")
		)
		(fp_line
			(start 0.2794 -0.1016)
			(end -0.2794 -0.1016)
			(stroke
				(width 0.1)
				(type default)
			)
			(layer "F.Fab")
		)
		(pad "1" smd rect
			(at 0 0 270)
			(size 0.508 0.508)
			(layers "F.Cu" "F.Mask" "F.Paste")
			(net "SVID_VDIO_PVDDQ_KLM")
		)
		(pad "2" smd rect
			(at 0 0.889 270)
			(size 0.508 0.508)
			(layers "F.Cu" "F.Mask" "F.Paste")
			(net "SVID_DIO1_CPU1_R")
		)
		(zone
			(layer "F.Cu")
			(hatch none 0.5)
			(connect_pads
				(clearance 0)
			)
			(min_thickness 0.25)
			(keepout
				(tracks allowed)
				(vias not_allowed)
				(pads allowed)
				(copperpour not_allowed)
				(footprints allowed)
			)
			(placement
				(enabled no)
				(sheetname "")
			)
			(fill
				(thermal_gap 0.5)
				(thermal_bridge_width 0.5)
				(island_removal_mode 0)
			)
			(polygon
				(pts
					(xy -3.1496 -127.4572) (xy -2.7686 -127.4572) (xy -2.7686 -127.9652) (xy -3.1496 -127.9652)
				)
			)
		)
		(zone
			(layer "F.Cu")
			(hatch none 0.5)
			(connect_pads
				(clearance 0)
			)
			(min_thickness 0.25)
			(keepout
				(tracks not_allowed)
				(vias allowed)
				(pads allowed)
				(copperpour not_allowed)
				(footprints allowed)
			)
			(placement
				(enabled no)
				(sheetname "")
			)
			(fill
				(thermal_gap 0.5)
				(thermal_bridge_width 0.5)
				(island_removal_mode 0)
			)
			(polygon
				(pts
					(xy -3.1496 -127.4572) (xy -2.7686 -127.4572) (xy -2.7686 -127.9652) (xy -3.1496 -127.9652)
				)
			)
		)
	)
	(footprint ""
		(layer "F.Cu")
		(at 272.861532 -149.8092 90)
		(property "Reference" "C5A8"
			(at 1.848866 0.752348 90)
			(unlocked yes)
			(layer "F.SilkS")
			(effects
				(font
					(size 1.27 0.9652)
					(thickness 0.1524)
				)
			)
		)
		(property "Value" ""
			(at 0 0 90)
			(layer "F.Fab")
			(effects
				(font
					(size 1.27 1.27)
				)
			)
		)
		(duplicate_pad_numbers_are_jumpers no)
		(fp_rect
			(start -0.500126 1.598422)
			(end 0.500126 -0.201422)
			(stroke
				(width 0)
				(type default)
			)
			(fill no)
			(layer "F.CrtYd")
		)
		(fp_line
			(start 0.500126 -0.201422)
			(end 0.500126 1.598422)
			(stroke
				(width 0.1)
				(type default)
			)
			(layer "F.Fab")
		)
		(fp_line
			(start -0.500126 -0.201422)
			(end 0.500126 -0.201422)
			(stroke
				(width 0.1)
				(type default)
			)
			(layer "F.Fab")
		)
		(fp_line
			(start 0.500126 1.598422)
			(end -0.500126 1.598422)
			(stroke
				(width 0.1)
				(type default)
			)
			(layer "F.Fab")
		)
		(fp_line
			(start -0.500126 1.598422)
			(end -0.500126 -0.201422)
			(stroke
				(width 0.1)
				(type default)
			)
			(layer "F.Fab")
		)
		(pad "1" smd rect
			(at 0 0)
			(size 0.889 0.9906)
			(layers "F.Cu" "F.Mask" "F.Paste")
			(net "PVDDQ_DEF")
		)
		(pad "2" smd rect
			(at 0 1.397)
			(size 0.889 0.9906)
			(layers "F.Cu" "F.Mask" "F.Paste")
			(net "GND")
		)
		(zone
			(layer "F.Cu")
			(hatch none 0.5)
			(connect_pads
				(clearance 0)
			)
			(min_thickness 0.25)
			(keepout
				(tracks allowed)
				(vias not_allowed)
				(pads allowed)
				(copperpour not_allowed)
				(footprints allowed)
			)
			(placement
				(enabled no)
				(sheetname "")
			)
			(fill
				(thermal_gap 0.5)
				(thermal_bridge_width 0.5)
				(island_removal_mode 0)
			)
			(polygon
				(pts
					(xy 273.814032 -149.3139) (xy 273.814032 -150.3045) (xy 273.306032 -150.3045) (xy 273.306032 -149.3139)
				)
			)
		)
		(zone
			(layer "F.Cu")
			(hatch none 0.5)
			(connect_pads
				(clearance 0)
			)
			(min_thickness 0.25)
			(keepout
				(tracks not_allowed)
				(vias allowed)
				(pads allowed)
				(copperpour not_allowed)
				(footprints allowed)
			)
			(placement
				(enabled no)
				(sheetname "")
			)
			(fill
				(thermal_gap 0.5)
				(thermal_bridge_width 0.5)
				(island_removal_mode 0)
			)
			(polygon
				(pts
					(xy 273.814032 -149.3139) (xy 273.814032 -150.3045) (xy 273.306032 -150.3045) (xy 273.306032 -149.3139)
				)
			)
		)
	)
	(footprint ""
		(layer "F.Cu")
		(at 201.396346 -52.7304 -90)
		(property "Reference" "RT2"
			(at 0 0 270)
			(layer "F.SilkS")
			(hide yes)
			(effects
				(font
					(size 1.27 1.27)
				)
			)
		)
		(property "Value" "*"
			(at -0.0254 -2.6289 270)
			(unlocked yes)
			(layer "F.Fab")
			(hide yes)
			(effects
				(font
					(size 1.27 1.016)
					(thickness 0.1524)
				)
			)
		)
		(property "Device Type" "1R3F-GP_RCL_GP-1R3F-GP,64.1R00A"
			(at -0.0254 -4.1529 270)
			(unlocked yes)
			(layer "F.Fab")
			(hide yes)
			(effects
				(font
					(size 1.27 1.016)
					(thickness 0.1524)
				)
			)
		)
		(duplicate_pad_numbers_are_jumpers no)
		(fp_line
			(start -0.4826 0)
			(end -0.2032 0)
			(stroke
				(width 0.2032)
				(type default)
			)
			(layer "F.SilkS")
		)
		(fp_line
			(start 0.2032 0)
			(end 0.4826 0)
			(stroke
				(width 0.2032)
				(type default)
			)
			(layer "F.SilkS")
		)
		(fp_rect
			(start -0.5842 1.3335)
			(end 0.5842 -1.3335)
			(stroke
				(width 0)
				(type default)
			)
			(fill no)
			(layer "F.CrtYd")
		)
		(fp_rect
			(start -0.5842 1.3335)
			(end 0.5842 -1.3335)
			(stroke
				(width 0)
				(type default)
			)
			(fill no)
			(layer "F.Fab")
		)
		(pad "1" smd custom
			(at 0 -0.762 270)
			(size 0.2159 0.2159)
			(layers "F.Cu" "F.Mask" "F.Paste")
			(net "VR_PVCCIN_CPU0_PHASE1_RC")
			(options
				(clearance outline)
				(anchor circle)
			)
			(primitives
				(gr_poly
					(pts
						(arc
							(start -0.3302 -0.4318)
							(mid -0.402042 -0.402042)
							(end -0.4318 -0.3302)
						)
						(arc
							(start -0.4318 0.3302)
							(mid -0.402042 0.402042)
							(end -0.3302 0.4318)
						)
						(arc
							(start 0.3302 0.4318)
							(mid 0.402042 0.402042)
							(end 0.4318 0.3302)
						)
						(arc
							(start 0.4318 -0.3302)
							(mid 0.402042 -0.402042)
							(end 0.3302 -0.4318)
						)
					)
					(width 0)
					(fill yes)
				)
			)
		)
		(pad "2" smd custom
			(at 0 0.762 270)
			(size 0.2159 0.2159)
			(layers "F.Cu" "F.Mask" "F.Paste")
			(net "GND")
			(options
				(clearance outline)
				(anchor circle)
			)
			(primitives
				(gr_poly
					(pts
						(arc
							(start -0.3302 -0.4318)
							(mid -0.402042 -0.402042)
							(end -0.4318 -0.3302)
						)
						(arc
							(start -0.4318 0.3302)
							(mid -0.402042 0.402042)
							(end -0.3302 0.4318)
						)
						(arc
							(start 0.3302 0.4318)
							(mid 0.402042 0.402042)
							(end 0.4318 0.3302)
						)
						(arc
							(start 0.4318 -0.3302)
							(mid 0.402042 -0.402042)
							(end 0.3302 -0.4318)
						)
					)
					(width 0)
					(fill yes)
				)
			)
		)
	)
	(footprint ""
		(layer "F.Cu")
		(at 22.225 -72.4662 90)
		(property "Reference" "R1D40"
			(at 0 0 90)
			(layer "F.SilkS")
			(hide yes)
			(effects
				(font
					(size 1.27 1.27)
				)
			)
		)
		(property "Value" ""
			(at 0 0 90)
			(layer "F.Fab")
			(effects
				(font
					(size 1.27 1.27)
				)
			)
		)
		(duplicate_pad_numbers_are_jumpers no)
		(fp_poly
			(pts
				(xy -0.2794 -0.1016) (xy 0.2794 -0.1016) (xy 0.2794 0.9906) (xy -0.2794 0.9906)
			)
			(stroke
				(width 0)
				(type default)
			)
			(fill no)
			(layer "F.CrtYd")
		)
		(fp_line
			(start 0.2794 -0.1016)
			(end -0.2794 -0.1016)
			(stroke
				(width 0.1)
				(type default)
			)
			(layer "F.Fab")
		)
		(fp_line
			(start -0.2794 -0.1016)
			(end -0.2794 0.9906)
			(stroke
				(width 0.1)
				(type default)
			)
			(layer "F.Fab")
		)
		(fp_line
			(start 0.2794 0.9906)
			(end 0.2794 -0.1016)
			(stroke
				(width 0.1)
				(type default)
			)
			(layer "F.Fab")
		)
		(fp_line
			(start -0.2794 0.9906)
			(end 0.2794 0.9906)
			(stroke
				(width 0.1)
				(type default)
			)
			(layer "F.Fab")
		)
		(pad "1" smd rect
			(at 0 0 90)
			(size 0.508 0.508)
			(layers "F.Cu" "F.Mask" "F.Paste")
			(net "A_HSC_PSET")
		)
		(pad "2" smd rect
			(at 0 0.889 90)
			(size 0.508 0.508)
			(layers "F.Cu" "F.Mask" "F.Paste")
			(net "AGND_HSC")
		)
		(zone
			(layer "F.Cu")
			(hatch none 0.5)
			(connect_pads
				(clearance 0)
			)
			(min_thickness 0.25)
			(keepout
				(tracks allowed)
				(vias not_allowed)
				(pads allowed)
				(copperpour not_allowed)
				(footprints allowed)
			)
			(placement
				(enabled no)
				(sheetname "")
			)
			(fill
				(thermal_gap 0.5)
				(thermal_bridge_width 0.5)
				(island_removal_mode 0)
			)
			(polygon
				(pts
					(xy 22.479 -72.2122) (xy 22.479 -72.7202) (xy 22.86 -72.7202) (xy 22.86 -72.2122)
				)
			)
		)
		(zone
			(layer "F.Cu")
			(hatch none 0.5)
			(connect_pads
				(clearance 0)
			)
			(min_thickness 0.25)
			(keepout
				(tracks not_allowed)
				(vias allowed)
				(pads allowed)
				(copperpour not_allowed)
				(footprints allowed)
			)
			(placement
				(enabled no)
				(sheetname "")
			)
			(fill
				(thermal_gap 0.5)
				(thermal_bridge_width 0.5)
				(island_removal_mode 0)
			)
			(polygon
				(pts
					(xy 22.86 -72.2122) (xy 22.86 -72.7202) (xy 22.479 -72.7202) (xy 22.479 -72.2122)
				)
			)
		)
	)
	(footprint ""
		(layer "F.Cu")
		(at 454.025 -150.241 180)
		(property "Reference" "R9A4"
			(at 0 0 180)
			(layer "F.SilkS")
			(hide yes)
			(effects
				(font
					(size 1.27 1.27)
				)
			)
		)
		(property "Value" ""
			(at 0 0 180)
			(layer "F.Fab")
			(effects
				(font
					(size 1.27 1.27)
				)
			)
		)
		(duplicate_pad_numbers_are_jumpers no)
		(fp_poly
			(pts
				(xy -0.2794 -0.1016) (xy 0.2794 -0.1016) (xy 0.2794 0.9906) (xy -0.2794 0.9906)
			)
			(stroke
				(width 0)
				(type default)
			)
			(fill no)
			(layer "F.CrtYd")
		)
		(fp_line
			(start 0.2794 0.9906)
			(end 0.2794 -0.1016)
			(stroke
				(width 0.1)
				(type default)
			)
			(layer "F.Fab")
		)
		(fp_line
			(start 0.2794 -0.1016)
			(end -0.2794 -0.1016)
			(stroke
				(width 0.1)
				(type default)
			)
			(layer "F.Fab")
		)
		(fp_line
			(start -0.2794 0.9906)
			(end 0.2794 0.9906)
			(stroke
				(width 0.1)
				(type default)
			)
			(layer "F.Fab")
		)
		(fp_line
			(start -0.2794 -0.1016)
			(end -0.2794 0.9906)
			(stroke
				(width 0.1)
				(type default)
			)
			(layer "F.Fab")
		)
		(pad "1" smd rect
			(at 0 0 180)
			(size 0.508 0.508)
			(layers "F.Cu" "F.Mask" "F.Paste")
			(net "CPU_XDP_PRESENT_N")
		)
		(pad "2" smd rect
			(at 0 0.889 180)
			(size 0.508 0.508)
			(layers "F.Cu" "F.Mask" "F.Paste")
			(net "PVCCIO_CPU0")
		)
		(zone
			(layer "F.Cu")
			(hatch none 0.5)
			(connect_pads
				(clearance 0)
			)
			(min_thickness 0.25)
			(keepout
				(tracks not_allowed)
				(vias allowed)
				(pads allowed)
				(copperpour not_allowed)
				(footprints allowed)
			)
			(placement
				(enabled no)
				(sheetname "")
			)
			(fill
				(thermal_gap 0.5)
				(thermal_bridge_width 0.5)
				(island_removal_mode 0)
			)
			(polygon
				(pts
					(xy 454.279 -150.876) (xy 453.771 -150.876) (xy 453.771 -150.495) (xy 454.279 -150.495)
				)
			)
		)
		(zone
			(layer "F.Cu")
			(hatch none 0.5)
			(connect_pads
				(clearance 0)
			)
			(min_thickness 0.25)
			(keepout
				(tracks allowed)
				(vias not_allowed)
				(pads allowed)
				(copperpour not_allowed)
				(footprints allowed)
			)
			(placement
				(enabled no)
				(sheetname "")
			)
			(fill
				(thermal_gap 0.5)
				(thermal_bridge_width 0.5)
				(island_removal_mode 0)
			)
			(polygon
				(pts
					(xy 454.279 -150.495) (xy 453.771 -150.495) (xy 453.771 -150.876) (xy 454.279 -150.876)
				)
			)
		)
	)
)
